G04 ================== begin FILE IDENTIFICATION RECORD ==================*
G04 Layout Name:  9051_F0T_Panel_BD_Front_D_v02_20221209_1310.brd*
G04 Film Name:    pmb*
G04 File Format:  Gerber RS274X*
G04 File Origin:  Cadence Allegro 17.2-S081*
G04 Origin Date:  Mon Dec 12 15:51:17 2022*
G04 *
G04 Layer:  DRAWING FORMAT/TITLE_BLOCK_A*
G04 Layer:  VIA CLASS/PASTEMASK_BOTTOM*
G04 Layer:  PIN/PASTEMASK_BOTTOM*
G04 Layer:  PACKAGE GEOMETRY/PASTEMASK_BOTTOM*
G04 Layer:  MANUFACTURING/PHOTOPLOT_OUTLINE*
G04 Layer:  DRAWING FORMAT/TITLE_BLOCK*
G04 Layer:  DRAWING FORMAT/TITLE_DATA_PMB*
G04 *
G04 Offset:    (0.00 0.00)*
G04 Mirror:    No*
G04 Mode:      Positive*
G04 Rotation:  0*
G04 FullContactRelief:  No*
G04 UndefLineWidth:     6.00*
G04 ================== end FILE IDENTIFICATION RECORD ====================*
%FSLAX25Y25*MOIN*%
%IR0*IPPOS*OFA0.00000B0.00000*MIA0B0*SFA1.00000B1.00000*%
%ADD16O,.052X.103*%
%ADD15C,.042*%
%ADD17C,.044*%
%ADD11C,.026*%
%ADD13C,.054*%
%ADD12C,.048*%
%ADD19R,.044X.044*%
%ADD14R,.054X.054*%
%ADD10R,.048X.048*%
%ADD18O,.052X.075*%
%ADD20C,.006*%
G75*
%LPD*%
G75*
G54D10*
X10315Y20079D03*
X33937D03*
G54D20*
G01X-117168Y-317735D02*
Y-322735D01*
G01X-118625Y-317735D02*
X-115711D01*
G01X-110801Y-322735D02*
X-113335D01*
Y-317735D01*
X-110801D01*
G01X-111815Y-320152D02*
X-113335D01*
G01X-108235Y-317735D02*
Y-322735D01*
X-105701D01*
G01X-101868Y-322902D02*
X-101995Y-322818D01*
Y-322652D01*
X-101868Y-322568D01*
X-101741Y-322652D01*
Y-322818D01*
X-101868Y-322902D01*
G01Y-320652D02*
X-101995Y-320568D01*
Y-320402D01*
X-101868Y-320318D01*
X-101741Y-320402D01*
Y-320568D01*
X-101868Y-320652D01*
G01X-97085Y-324402D02*
X-97718Y-323568D01*
X-98035Y-322735D01*
Y-319402D01*
X-97718Y-318568D01*
X-97085Y-317735D01*
G01X-91668D02*
X-92175Y-317902D01*
X-92555Y-318318D01*
X-92808Y-318818D01*
X-92998Y-319485D01*
X-93061Y-320235D01*
X-92998Y-320985D01*
X-92808Y-321652D01*
X-92555Y-322152D01*
X-92175Y-322568D01*
X-91668Y-322735D01*
X-91161Y-322568D01*
X-90781Y-322152D01*
X-90528Y-321652D01*
X-90338Y-320985D01*
X-90275Y-320235D01*
X-90338Y-319485D01*
X-90528Y-318818D01*
X-90781Y-318318D01*
X-91161Y-317902D01*
X-91668Y-317735D01*
G01X-87961Y-321735D02*
X-87581Y-322318D01*
X-87075Y-322652D01*
X-86505Y-322735D01*
X-85998Y-322652D01*
X-85491Y-322235D01*
X-85175Y-321735D01*
X-85111Y-321235D01*
X-85238Y-320652D01*
X-85681Y-320235D01*
X-86125Y-320068D01*
X-86695D01*
G01X-86125D02*
X-85745Y-319818D01*
X-85428Y-319402D01*
X-85301Y-318902D01*
X-85428Y-318402D01*
X-85745Y-317985D01*
X-86315Y-317735D01*
X-86885Y-317818D01*
X-87455Y-318152D01*
G01X-81151Y-324402D02*
X-80518Y-323568D01*
X-80201Y-322735D01*
Y-319402D01*
X-80518Y-318568D01*
X-81151Y-317735D01*
G01X-77761Y-321735D02*
X-77381Y-322318D01*
X-76875Y-322652D01*
X-76305Y-322735D01*
X-75798Y-322652D01*
X-75291Y-322235D01*
X-74975Y-321735D01*
X-74911Y-321235D01*
X-75038Y-320652D01*
X-75481Y-320235D01*
X-75925Y-320068D01*
X-76495D01*
G01X-75925D02*
X-75545Y-319818D01*
X-75228Y-319402D01*
X-75101Y-318902D01*
X-75228Y-318402D01*
X-75545Y-317985D01*
X-76115Y-317735D01*
X-76685Y-317818D01*
X-77255Y-318152D01*
G01X-72471Y-318568D02*
X-72091Y-318068D01*
X-71648Y-317818D01*
X-71141Y-317735D01*
X-70508Y-317902D01*
X-70065Y-318318D01*
X-69938Y-318818D01*
X-70001Y-319318D01*
X-70255Y-319735D01*
X-71521Y-320568D01*
X-72091Y-321152D01*
X-72471Y-321985D01*
X-72598Y-322735D01*
X-69938D01*
G01X-66295D02*
X-66168Y-321652D01*
X-65978Y-320735D01*
X-65725Y-319902D01*
X-65408Y-318985D01*
X-64901Y-317735D01*
X-67435D01*
G01X-61891Y-321068D02*
X-60245D01*
G01X-57171Y-318568D02*
X-56791Y-318068D01*
X-56348Y-317818D01*
X-55841Y-317735D01*
X-55208Y-317902D01*
X-54765Y-318318D01*
X-54638Y-318818D01*
X-54701Y-319318D01*
X-54955Y-319735D01*
X-56221Y-320568D01*
X-56791Y-321152D01*
X-57171Y-321985D01*
X-57298Y-322735D01*
X-54638D01*
G01X-52261Y-321735D02*
X-51881Y-322318D01*
X-51375Y-322652D01*
X-50805Y-322735D01*
X-50298Y-322652D01*
X-49791Y-322235D01*
X-49475Y-321735D01*
X-49411Y-321235D01*
X-49538Y-320652D01*
X-49981Y-320235D01*
X-50425Y-320068D01*
X-50995D01*
G01X-50425D02*
X-50045Y-319818D01*
X-49728Y-319402D01*
X-49601Y-318902D01*
X-49728Y-318402D01*
X-50045Y-317985D01*
X-50615Y-317735D01*
X-51185Y-317818D01*
X-51755Y-318152D01*
G01X-45008Y-322735D02*
Y-317735D01*
X-47351Y-321318D01*
X-44185D01*
G01X-42061Y-321985D02*
X-41681Y-322402D01*
X-41238Y-322652D01*
X-40668Y-322735D01*
X-40098Y-322568D01*
X-39655Y-322235D01*
X-39338Y-321652D01*
X-39275Y-320985D01*
X-39401Y-320318D01*
X-39718Y-319902D01*
X-40161Y-319568D01*
X-40605Y-319485D01*
X-41048Y-319568D01*
X-41618Y-319902D01*
X-41428Y-317735D01*
X-39718D01*
G01X-31671Y-322735D02*
Y-317735D01*
X-29265D01*
G01X-30151Y-320152D02*
X-31671D01*
G01X-26951Y-322735D02*
X-25368Y-317735D01*
X-23785Y-322735D01*
G01X-24355Y-320985D02*
X-26381D01*
G01X-21598Y-322735D02*
X-18938Y-317735D01*
G01X-21598D02*
X-18938Y-322735D01*
G01X-15168Y-322902D02*
X-15295Y-322818D01*
Y-322652D01*
X-15168Y-322568D01*
X-15041Y-322652D01*
Y-322818D01*
X-15168Y-322902D01*
G01Y-320652D02*
X-15295Y-320568D01*
Y-320402D01*
X-15168Y-320318D01*
X-15041Y-320402D01*
Y-320568D01*
X-15168Y-320652D01*
G01X-10385Y-324402D02*
X-11018Y-323568D01*
X-11335Y-322735D01*
Y-319402D01*
X-11018Y-318568D01*
X-10385Y-317735D01*
G01X-4968D02*
X-5475Y-317902D01*
X-5855Y-318318D01*
X-6108Y-318818D01*
X-6298Y-319485D01*
X-6361Y-320235D01*
X-6298Y-320985D01*
X-6108Y-321652D01*
X-5855Y-322152D01*
X-5475Y-322568D01*
X-4968Y-322735D01*
X-4461Y-322568D01*
X-4081Y-322152D01*
X-3828Y-321652D01*
X-3638Y-320985D01*
X-3575Y-320235D01*
X-3638Y-319485D01*
X-3828Y-318818D01*
X-4081Y-318318D01*
X-4461Y-317902D01*
X-4968Y-317735D01*
G01X-1261Y-321735D02*
X-881Y-322318D01*
X-375Y-322652D01*
X195Y-322735D01*
X702Y-322652D01*
X1209Y-322235D01*
X1525Y-321735D01*
X1589Y-321235D01*
X1462Y-320652D01*
X1019Y-320235D01*
X575Y-320068D01*
X5D01*
G01X575D02*
X955Y-319818D01*
X1272Y-319402D01*
X1399Y-318902D01*
X1272Y-318402D01*
X955Y-317985D01*
X385Y-317735D01*
X-185Y-317818D01*
X-755Y-318152D01*
G01X5549Y-324402D02*
X6182Y-323568D01*
X6499Y-322735D01*
Y-319402D01*
X6182Y-318568D01*
X5549Y-317735D01*
G01X8939Y-321735D02*
X9319Y-322318D01*
X9825Y-322652D01*
X10395Y-322735D01*
X10902Y-322652D01*
X11409Y-322235D01*
X11725Y-321735D01*
X11789Y-321235D01*
X11662Y-320652D01*
X11219Y-320235D01*
X10775Y-320068D01*
X10205D01*
G01X10775D02*
X11155Y-319818D01*
X11472Y-319402D01*
X11599Y-318902D01*
X11472Y-318402D01*
X11155Y-317985D01*
X10585Y-317735D01*
X10015Y-317818D01*
X9445Y-318152D01*
G01X14355Y-322152D02*
X14799Y-322568D01*
X15305Y-322735D01*
X15812Y-322568D01*
X16255Y-322068D01*
X16572Y-321318D01*
X16699Y-320568D01*
Y-319652D01*
X16572Y-318902D01*
X16255Y-318235D01*
X15875Y-317902D01*
X15432Y-317735D01*
X14925Y-317902D01*
X14545Y-318235D01*
X14292Y-318735D01*
X14165Y-319402D01*
X14292Y-319985D01*
X14609Y-320568D01*
X14989Y-320902D01*
X15432Y-320985D01*
X15939Y-320818D01*
X16319Y-320402D01*
X16699Y-319652D01*
G01X20405Y-322735D02*
X20532Y-321652D01*
X20722Y-320735D01*
X20975Y-319902D01*
X21292Y-318985D01*
X21799Y-317735D01*
X19265D01*
G01X24809Y-321068D02*
X26455D01*
G01X29339Y-321735D02*
X29719Y-322318D01*
X30225Y-322652D01*
X30795Y-322735D01*
X31302Y-322652D01*
X31809Y-322235D01*
X32125Y-321735D01*
X32189Y-321235D01*
X32062Y-320652D01*
X31619Y-320235D01*
X31175Y-320068D01*
X30605D01*
G01X31175D02*
X31555Y-319818D01*
X31872Y-319402D01*
X31999Y-318902D01*
X31872Y-318402D01*
X31555Y-317985D01*
X30985Y-317735D01*
X30415Y-317818D01*
X29845Y-318152D01*
G01X34629Y-320652D02*
X35072Y-320068D01*
X35452Y-319735D01*
X35959Y-319568D01*
X36402Y-319735D01*
X36719Y-320068D01*
X36972Y-320568D01*
X37035Y-321152D01*
X36972Y-321652D01*
X36719Y-322152D01*
X36339Y-322568D01*
X35895Y-322735D01*
X35389Y-322568D01*
X34945Y-322068D01*
X34692Y-321318D01*
X34629Y-320485D01*
X34755Y-319402D01*
X34945Y-318818D01*
X35262Y-318235D01*
X35705Y-317818D01*
X36149Y-317735D01*
X36592Y-317902D01*
X36909Y-318318D01*
G01X40932Y-322735D02*
Y-317735D01*
X40172Y-318735D01*
G01Y-322735D02*
X41692D01*
G01X46792D02*
Y-317735D01*
X44449Y-321318D01*
X47615D01*
G01X-129168Y-252735D02*
Y-327735D01*
X370832D01*
Y-252735D01*
X-129168D01*
G01X65832D02*
Y-327735D01*
G01Y-302735D02*
X168832D01*
Y-277735D01*
G01X65832D02*
X168832D01*
G01X176339Y-312735D02*
Y-307735D01*
X177605D01*
X178112Y-307985D01*
X178492Y-308318D01*
X178809Y-308818D01*
X179062Y-309402D01*
X179125Y-310235D01*
X179062Y-311068D01*
X178809Y-311652D01*
X178492Y-312152D01*
X178112Y-312485D01*
X177605Y-312735D01*
X176339D01*
G01X181249D02*
X182832Y-307735D01*
X184415Y-312735D01*
G01X183845Y-310985D02*
X181819D01*
G01X187932Y-307735D02*
Y-312735D01*
G01X186475Y-307735D02*
X189389D01*
G01X194299Y-312735D02*
X191765D01*
Y-307735D01*
X194299D01*
G01X193285Y-310152D02*
X191765D01*
G01X198132Y-312902D02*
X198005Y-312818D01*
Y-312652D01*
X198132Y-312568D01*
X198259Y-312652D01*
Y-312818D01*
X198132Y-312902D01*
G01Y-310652D02*
X198005Y-310568D01*
Y-310402D01*
X198132Y-310318D01*
X198259Y-310402D01*
Y-310568D01*
X198132Y-310652D01*
G01X170832Y-252735D02*
Y-327735D01*
G01X168832Y-252735D02*
Y-327735D01*
G01X170832Y-302735D02*
X370832D01*
G01X176465Y-287735D02*
Y-282735D01*
X177985D01*
X178492Y-282985D01*
X178872Y-283568D01*
X178999Y-284235D01*
X178872Y-284902D01*
X178555Y-285402D01*
X177985Y-285652D01*
X176465D01*
G01X181692Y-287902D02*
X183972Y-282735D01*
G01X186475Y-287735D02*
Y-282735D01*
X189389Y-287735D01*
Y-282735D01*
G01X193032Y-287902D02*
X192905Y-287818D01*
Y-287652D01*
X193032Y-287568D01*
X193159Y-287652D01*
Y-287818D01*
X193032Y-287902D01*
G01Y-285652D02*
X192905Y-285568D01*
Y-285402D01*
X193032Y-285318D01*
X193159Y-285402D01*
Y-285568D01*
X193032Y-285652D01*
G01X170832Y-277735D02*
X370832D01*
G01X176465Y-262735D02*
Y-257735D01*
X177985D01*
X178492Y-257985D01*
X178872Y-258568D01*
X178999Y-259235D01*
X178872Y-259902D01*
X178555Y-260402D01*
X177985Y-260652D01*
X176465D01*
G01X181565Y-262735D02*
Y-257735D01*
X183149D01*
X183655Y-257985D01*
X183972Y-258318D01*
X184099Y-258985D01*
X183972Y-259652D01*
X183592Y-260068D01*
X183149Y-260318D01*
X181565D01*
G01X183149D02*
X184099Y-262735D01*
G01X187932D02*
X187425Y-262652D01*
X186982Y-262318D01*
X186602Y-261818D01*
X186349Y-261235D01*
X186222Y-260568D01*
Y-259902D01*
X186349Y-259235D01*
X186602Y-258652D01*
X186982Y-258152D01*
X187425Y-257818D01*
X187932Y-257735D01*
X188439Y-257818D01*
X188882Y-258152D01*
X189262Y-258652D01*
X189515Y-259235D01*
X189642Y-259902D01*
Y-260568D01*
X189515Y-261235D01*
X189262Y-261818D01*
X188882Y-262318D01*
X188439Y-262652D01*
X187932Y-262735D01*
G01X191765Y-261735D02*
X192082Y-262235D01*
X192462Y-262568D01*
X192905Y-262735D01*
X193412Y-262568D01*
X193792Y-262235D01*
X194172Y-261735D01*
X194299Y-261068D01*
Y-257735D01*
G01X199399Y-262735D02*
X196865D01*
Y-257735D01*
X199399D01*
G01X198385Y-260152D02*
X196865D01*
G01X204625Y-258152D02*
X204245Y-257902D01*
X203802Y-257735D01*
X203295D01*
X202725Y-257985D01*
X202282Y-258402D01*
X201965Y-258902D01*
X201712Y-259735D01*
X201649Y-260485D01*
X201775Y-261235D01*
X201965Y-261735D01*
X202345Y-262235D01*
X202789Y-262568D01*
X203232Y-262735D01*
X203675D01*
X204119Y-262568D01*
X204499Y-262318D01*
X204815Y-261985D01*
G01X208332Y-257735D02*
Y-262735D01*
G01X206875Y-257735D02*
X209789D01*
G01X213432Y-262902D02*
X213305Y-262818D01*
Y-262652D01*
X213432Y-262568D01*
X213559Y-262652D01*
Y-262818D01*
X213432Y-262902D01*
G01Y-260652D02*
X213305Y-260568D01*
Y-260402D01*
X213432Y-260318D01*
X213559Y-260402D01*
Y-260568D01*
X213432Y-260652D01*
G01X283832Y-302735D02*
Y-327735D01*
G01X288465Y-305235D02*
Y-310235D01*
X290999D01*
G01X294072Y-305235D02*
X295592D01*
G01X294832D02*
Y-310235D01*
G01X294072D02*
X295592D01*
G01X300439Y-307568D02*
X300692Y-307318D01*
X300882Y-306902D01*
X301009Y-306318D01*
X300882Y-305818D01*
X300629Y-305485D01*
X300185Y-305235D01*
X298475D01*
Y-310235D01*
X300565D01*
X301009Y-309902D01*
X301262Y-309402D01*
X301389Y-308818D01*
X301262Y-308235D01*
X300882Y-307735D01*
X300439Y-307568D01*
X298475D01*
G01X305032Y-310402D02*
X304905Y-310318D01*
Y-310152D01*
X305032Y-310068D01*
X305159Y-310152D01*
Y-310318D01*
X305032Y-310402D01*
G01Y-308152D02*
X304905Y-308068D01*
Y-307902D01*
X305032Y-307818D01*
X305159Y-307902D01*
Y-308068D01*
X305032Y-308152D01*
G01X328832Y-302735D02*
Y-327735D01*
G01X332732Y-305235D02*
Y-310235D01*
G01X331275Y-305235D02*
X334189D01*
G01X337832Y-310235D02*
X337452Y-310152D01*
X337072Y-309818D01*
X336819Y-309235D01*
X336692Y-308568D01*
X336819Y-307902D01*
X337072Y-307318D01*
X337452Y-306985D01*
X337832Y-306902D01*
X338212Y-306985D01*
X338592Y-307318D01*
X338845Y-307902D01*
X338909Y-308568D01*
X338845Y-309235D01*
X338592Y-309818D01*
X338212Y-310152D01*
X337832Y-310235D01*
G01X342932D02*
X342552Y-310152D01*
X342172Y-309818D01*
X341919Y-309235D01*
X341792Y-308568D01*
X341919Y-307902D01*
X342172Y-307318D01*
X342552Y-306985D01*
X342932Y-306902D01*
X343312Y-306985D01*
X343692Y-307318D01*
X343945Y-307902D01*
X344009Y-308568D01*
X343945Y-309235D01*
X343692Y-309818D01*
X343312Y-310152D01*
X342932Y-310235D01*
G01X348032D02*
Y-305235D01*
G01X353132Y-310402D02*
X353005Y-310318D01*
Y-310152D01*
X353132Y-310068D01*
X353259Y-310152D01*
Y-310318D01*
X353132Y-310402D01*
G01Y-308152D02*
X353005Y-308068D01*
Y-307902D01*
X353132Y-307818D01*
X353259Y-307902D01*
Y-308068D01*
X353132Y-308152D01*
G01X328832Y-277735D02*
Y-302735D01*
G01X331465Y-285235D02*
Y-280235D01*
X333049D01*
X333555Y-280485D01*
X333872Y-280818D01*
X333999Y-281485D01*
X333872Y-282152D01*
X333492Y-282568D01*
X333049Y-282818D01*
X331465D01*
G01X333049D02*
X333999Y-285235D01*
G01X339099D02*
X336565D01*
Y-280235D01*
X339099D01*
G01X338085Y-282652D02*
X336565D01*
G01X341349Y-280235D02*
X342932Y-285235D01*
X344515Y-280235D01*
G01X348032Y-285402D02*
X347905Y-285318D01*
Y-285152D01*
X348032Y-285068D01*
X348159Y-285152D01*
Y-285318D01*
X348032Y-285402D01*
G01Y-283152D02*
X347905Y-283068D01*
Y-282902D01*
X348032Y-282818D01*
X348159Y-282902D01*
Y-283068D01*
X348032Y-283152D01*
G01X351592Y-329435D02*
X351672Y-329360D01*
X351732Y-329235D01*
X351772Y-329060D01*
X351732Y-328910D01*
X351652Y-328810D01*
X351512Y-328735D01*
X350972D01*
Y-330235D01*
X351632D01*
X351772Y-330135D01*
X351852Y-329985D01*
X351892Y-329810D01*
X351852Y-329635D01*
X351732Y-329485D01*
X351592Y-329435D01*
X350972D01*
G01X352992Y-330235D02*
Y-329235D01*
G01Y-329410D02*
X352912Y-329310D01*
X352792Y-329260D01*
X352652Y-329235D01*
X352512Y-329285D01*
X352392Y-329385D01*
X352312Y-329535D01*
X352272Y-329735D01*
X352312Y-329935D01*
X352392Y-330085D01*
X352512Y-330185D01*
X352652Y-330235D01*
X352792Y-330210D01*
X352912Y-330135D01*
X352992Y-330035D01*
G01X353532Y-330060D02*
X353632Y-330160D01*
X353772Y-330235D01*
X353892D01*
X354012Y-330185D01*
X354092Y-330110D01*
X354132Y-330010D01*
X354112Y-329860D01*
X354032Y-329785D01*
X353672Y-329635D01*
X353592Y-329460D01*
X353632Y-329335D01*
X353712Y-329260D01*
X353832Y-329235D01*
X353952Y-329260D01*
X354072Y-329335D01*
G01X354732Y-329560D02*
X355372D01*
X355312Y-329385D01*
X355212Y-329285D01*
X355072Y-329235D01*
X354932Y-329260D01*
X354812Y-329335D01*
X354732Y-329510D01*
X354692Y-329660D01*
Y-329810D01*
X354732Y-329960D01*
X354832Y-330110D01*
X354952Y-330210D01*
X355092Y-330235D01*
X355232Y-330185D01*
X355372Y-330035D01*
G01X355872Y-330235D02*
Y-328735D01*
G01Y-329485D02*
X355972Y-329335D01*
X356092Y-329260D01*
X356212Y-329235D01*
X356392Y-329285D01*
X356512Y-329385D01*
X356592Y-329560D01*
Y-329760D01*
X356552Y-329960D01*
X356472Y-330110D01*
X356332Y-330210D01*
X356212Y-330235D01*
X356092Y-330210D01*
X355972Y-330135D01*
X355872Y-330010D01*
G01X357432Y-330235D02*
X357312Y-330210D01*
X357192Y-330110D01*
X357112Y-329935D01*
X357072Y-329735D01*
X357112Y-329535D01*
X357192Y-329360D01*
X357312Y-329260D01*
X357432Y-329235D01*
X357552Y-329260D01*
X357672Y-329360D01*
X357752Y-329535D01*
X357772Y-329735D01*
X357752Y-329935D01*
X357672Y-330110D01*
X357552Y-330210D01*
X357432Y-330235D01*
G01X358992D02*
Y-329235D01*
G01Y-329410D02*
X358912Y-329310D01*
X358792Y-329260D01*
X358652Y-329235D01*
X358512Y-329285D01*
X358392Y-329385D01*
X358312Y-329535D01*
X358272Y-329735D01*
X358312Y-329935D01*
X358392Y-330085D01*
X358512Y-330185D01*
X358652Y-330235D01*
X358792Y-330210D01*
X358912Y-330135D01*
X358992Y-330035D01*
G01X359552Y-330235D02*
Y-329235D01*
G01Y-329435D02*
X359652Y-329335D01*
X359752Y-329260D01*
X359892Y-329235D01*
X359992Y-329260D01*
X360112Y-329335D01*
G01X361392Y-328735D02*
Y-330235D01*
G01Y-330010D02*
X361312Y-330135D01*
X361192Y-330210D01*
X361052Y-330235D01*
X360892Y-330185D01*
X360772Y-330060D01*
X360692Y-329910D01*
X360672Y-329735D01*
X360692Y-329560D01*
X360772Y-329410D01*
X360892Y-329285D01*
X361052Y-329235D01*
X361192Y-329260D01*
X361292Y-329310D01*
X361392Y-329410D01*
G01X363032Y-330235D02*
Y-328735D01*
X363532D01*
X363692Y-328810D01*
X363792Y-328910D01*
X363832Y-329110D01*
X363792Y-329310D01*
X363672Y-329435D01*
X363532Y-329510D01*
X363032D01*
G01X363532D02*
X363832Y-330235D01*
G01X364332Y-329560D02*
X364972D01*
X364912Y-329385D01*
X364812Y-329285D01*
X364672Y-329235D01*
X364532Y-329260D01*
X364412Y-329335D01*
X364332Y-329510D01*
X364292Y-329660D01*
Y-329810D01*
X364332Y-329960D01*
X364432Y-330110D01*
X364552Y-330210D01*
X364692Y-330235D01*
X364832Y-330185D01*
X364972Y-330035D01*
G01X365472Y-329235D02*
X365832Y-330235D01*
X366192Y-329235D01*
G01X367032Y-330285D02*
X366992Y-330260D01*
Y-330210D01*
X367032Y-330185D01*
X367072Y-330210D01*
Y-330260D01*
X367032Y-330285D01*
G01X368192Y-330235D02*
X368232Y-329910D01*
X368292Y-329635D01*
X368372Y-329385D01*
X368472Y-329110D01*
X368632Y-328735D01*
X367832D01*
G01X369592Y-329435D02*
X369672Y-329360D01*
X369732Y-329235D01*
X369772Y-329060D01*
X369732Y-328910D01*
X369652Y-328810D01*
X369512Y-328735D01*
X368972D01*
Y-330235D01*
X369632D01*
X369772Y-330135D01*
X369852Y-329985D01*
X369892Y-329810D01*
X369852Y-329635D01*
X369732Y-329485D01*
X369592Y-329435D01*
X368972D01*
G01X-247901Y-428634D02*
Y1008173D01*
X2091018D01*
Y-428634D01*
X-247901D01*
G01X-115095Y-307460D02*
X-115565Y-307145D01*
X-116113Y-306935D01*
X-116740D01*
X-117445Y-307250D01*
X-117993Y-307775D01*
X-118385Y-308405D01*
X-118698Y-309455D01*
X-118776Y-310400D01*
X-118620Y-311345D01*
X-118385Y-311975D01*
X-117915Y-312605D01*
X-117366Y-313025D01*
X-116818Y-313235D01*
X-116270D01*
X-115721Y-313025D01*
X-115251Y-312710D01*
X-114860Y-312290D01*
G01X-111458Y-306935D02*
X-109578D01*
G01X-110518D02*
Y-313235D01*
G01X-111458D02*
X-109578D01*
G01X-104218Y-306935D02*
Y-313235D01*
G01X-106020Y-306935D02*
X-102416D01*
G01X-97918Y-313235D02*
Y-310400D01*
X-99485Y-306935D01*
G01X-96351D02*
X-97918Y-310400D01*
G01X-87041Y-311975D02*
X-86571Y-312710D01*
X-85945Y-313130D01*
X-85240Y-313235D01*
X-84613Y-313130D01*
X-83986Y-312605D01*
X-83595Y-311975D01*
X-83516Y-311345D01*
X-83673Y-310610D01*
X-84221Y-310085D01*
X-84770Y-309875D01*
X-85475D01*
G01X-84770D02*
X-84300Y-309560D01*
X-83908Y-309035D01*
X-83751Y-308405D01*
X-83908Y-307775D01*
X-84300Y-307250D01*
X-85005Y-306935D01*
X-85710Y-307040D01*
X-86415Y-307460D01*
G01X-80741Y-311975D02*
X-80271Y-312710D01*
X-79645Y-313130D01*
X-78940Y-313235D01*
X-78313Y-313130D01*
X-77686Y-312605D01*
X-77295Y-311975D01*
X-77216Y-311345D01*
X-77373Y-310610D01*
X-77921Y-310085D01*
X-78470Y-309875D01*
X-79175D01*
G01X-78470D02*
X-78000Y-309560D01*
X-77608Y-309035D01*
X-77451Y-308405D01*
X-77608Y-307775D01*
X-78000Y-307250D01*
X-78705Y-306935D01*
X-79410Y-307040D01*
X-80115Y-307460D01*
G01X-74441Y-311975D02*
X-73971Y-312710D01*
X-73345Y-313130D01*
X-72640Y-313235D01*
X-72013Y-313130D01*
X-71386Y-312605D01*
X-70995Y-311975D01*
X-70916Y-311345D01*
X-71073Y-310610D01*
X-71621Y-310085D01*
X-72170Y-309875D01*
X-72875D01*
G01X-72170D02*
X-71700Y-309560D01*
X-71308Y-309035D01*
X-71151Y-308405D01*
X-71308Y-307775D01*
X-71700Y-307250D01*
X-72405Y-306935D01*
X-73110Y-307040D01*
X-73815Y-307460D01*
G01X-66575Y-313235D02*
X-66418Y-311870D01*
X-66183Y-310715D01*
X-65870Y-309665D01*
X-65478Y-308510D01*
X-64851Y-306935D01*
X-67985D01*
G01X-60275Y-313235D02*
X-60118Y-311870D01*
X-59883Y-310715D01*
X-59570Y-309665D01*
X-59178Y-308510D01*
X-58551Y-306935D01*
X-61685D01*
G01X-53975Y-314390D02*
X-53661Y-313025D01*
G01X-47518Y-306935D02*
Y-313235D01*
G01X-49320Y-306935D02*
X-45716D01*
G01X-43176Y-313235D02*
X-41218Y-306935D01*
X-39260Y-313235D01*
G01X-39965Y-311030D02*
X-42471D01*
G01X-35858Y-306935D02*
X-33978D01*
G01X-34918D02*
Y-313235D01*
G01X-35858D02*
X-33978D01*
G01X-30968Y-306935D02*
X-29871Y-313235D01*
X-28618Y-306935D01*
X-27365Y-313235D01*
X-26268Y-306935D01*
G01X-24276Y-313235D02*
X-22318Y-306935D01*
X-20360Y-313235D01*
G01X-21065Y-311030D02*
X-23571D01*
G01X-17820Y-313235D02*
Y-306935D01*
X-14216Y-313235D01*
Y-306935D01*
G01X-3810Y-315335D02*
X-4593Y-314285D01*
X-4985Y-313235D01*
Y-309035D01*
X-4593Y-307985D01*
X-3810Y-306935D01*
G01X7615Y-313235D02*
Y-306935D01*
X9574D01*
X10200Y-307250D01*
X10592Y-307670D01*
X10749Y-308510D01*
X10592Y-309350D01*
X10122Y-309875D01*
X9574Y-310190D01*
X7615D01*
G01X9574D02*
X10749Y-313235D01*
G01X15482Y-313445D02*
X15325Y-313340D01*
Y-313130D01*
X15482Y-313025D01*
X15639Y-313130D01*
Y-313340D01*
X15482Y-313445D01*
G01X21782Y-313235D02*
X21155Y-313130D01*
X20607Y-312710D01*
X20137Y-312080D01*
X19824Y-311345D01*
X19667Y-310505D01*
Y-309665D01*
X19824Y-308825D01*
X20137Y-308090D01*
X20607Y-307460D01*
X21155Y-307040D01*
X21782Y-306935D01*
X22409Y-307040D01*
X22957Y-307460D01*
X23427Y-308090D01*
X23740Y-308825D01*
X23897Y-309665D01*
Y-310505D01*
X23740Y-311345D01*
X23427Y-312080D01*
X22957Y-312710D01*
X22409Y-313130D01*
X21782Y-313235D01*
G01X28082Y-313445D02*
X27925Y-313340D01*
Y-313130D01*
X28082Y-313025D01*
X28239Y-313130D01*
Y-313340D01*
X28082Y-313445D01*
G01X36105Y-307460D02*
X35635Y-307145D01*
X35087Y-306935D01*
X34460D01*
X33755Y-307250D01*
X33207Y-307775D01*
X32815Y-308405D01*
X32502Y-309455D01*
X32424Y-310400D01*
X32580Y-311345D01*
X32815Y-311975D01*
X33285Y-312605D01*
X33834Y-313025D01*
X34382Y-313235D01*
X34930D01*
X35479Y-313025D01*
X35949Y-312710D01*
X36340Y-312290D01*
G01X40682Y-313445D02*
X40525Y-313340D01*
Y-313130D01*
X40682Y-313025D01*
X40839Y-313130D01*
Y-313340D01*
X40682Y-313445D01*
G01X47374Y-315335D02*
X48157Y-314285D01*
X48549Y-313235D01*
Y-309035D01*
X48157Y-307985D01*
X47374Y-306935D01*
G01X-118620Y-293235D02*
Y-286935D01*
X-115016Y-293235D01*
Y-286935D01*
G01X-110518Y-293235D02*
X-111145Y-293130D01*
X-111693Y-292710D01*
X-112163Y-292080D01*
X-112476Y-291345D01*
X-112633Y-290505D01*
Y-289665D01*
X-112476Y-288825D01*
X-112163Y-288090D01*
X-111693Y-287460D01*
X-111145Y-287040D01*
X-110518Y-286935D01*
X-109891Y-287040D01*
X-109343Y-287460D01*
X-108873Y-288090D01*
X-108560Y-288825D01*
X-108403Y-289665D01*
Y-290505D01*
X-108560Y-291345D01*
X-108873Y-292080D01*
X-109343Y-292710D01*
X-109891Y-293130D01*
X-110518Y-293235D01*
G01X-104218Y-293445D02*
X-104375Y-293340D01*
Y-293130D01*
X-104218Y-293025D01*
X-104061Y-293130D01*
Y-293340D01*
X-104218Y-293445D01*
G01X-99406Y-287985D02*
X-98936Y-287355D01*
X-98388Y-287040D01*
X-97761Y-286935D01*
X-96978Y-287145D01*
X-96430Y-287670D01*
X-96273Y-288300D01*
X-96351Y-288930D01*
X-96665Y-289455D01*
X-98231Y-290505D01*
X-98936Y-291240D01*
X-99406Y-292290D01*
X-99563Y-293235D01*
X-96273D01*
G01X-91618D02*
Y-286935D01*
X-92558Y-288195D01*
G01Y-293235D02*
X-90678D01*
G01X-85318D02*
Y-286935D01*
X-86258Y-288195D01*
G01Y-293235D02*
X-84378D01*
G01X-79175Y-294390D02*
X-78861Y-293025D01*
G01X-75068Y-286935D02*
X-73971Y-293235D01*
X-72718Y-286935D01*
X-71465Y-293235D01*
X-70368Y-286935D01*
G01X-64851Y-293235D02*
X-67985D01*
Y-286935D01*
X-64851D01*
G01X-66105Y-289980D02*
X-67985D01*
G01X-61920Y-293235D02*
Y-286935D01*
X-58316Y-293235D01*
Y-286935D01*
G01X-55463Y-293235D02*
Y-286935D01*
G01X-52173D02*
Y-293235D01*
G01Y-290085D02*
X-55463D01*
G01X-49241Y-286935D02*
Y-291450D01*
X-48928Y-292395D01*
X-48301Y-293025D01*
X-47518Y-293235D01*
X-46735Y-293025D01*
X-46108Y-292395D01*
X-45795Y-291450D01*
Y-286935D01*
G01X-43176Y-293235D02*
X-41218Y-286935D01*
X-39260Y-293235D01*
G01X-39965Y-291030D02*
X-42471D01*
G01X-30106Y-287985D02*
X-29636Y-287355D01*
X-29088Y-287040D01*
X-28461Y-286935D01*
X-27678Y-287145D01*
X-27130Y-287670D01*
X-26973Y-288300D01*
X-27051Y-288930D01*
X-27365Y-289455D01*
X-28931Y-290505D01*
X-29636Y-291240D01*
X-30106Y-292290D01*
X-30263Y-293235D01*
X-26973D01*
G01X-24120D02*
Y-286935D01*
X-20516Y-293235D01*
Y-286935D01*
G01X-17741Y-293235D02*
Y-286935D01*
X-16175D01*
X-15548Y-287250D01*
X-15078Y-287670D01*
X-14686Y-288300D01*
X-14373Y-289035D01*
X-14295Y-290085D01*
X-14373Y-291135D01*
X-14686Y-291870D01*
X-15078Y-292500D01*
X-15548Y-292920D01*
X-16175Y-293235D01*
X-17741D01*
G01X-4985D02*
Y-286935D01*
X-3026D01*
X-2400Y-287250D01*
X-2008Y-287670D01*
X-1851Y-288510D01*
X-2008Y-289350D01*
X-2478Y-289875D01*
X-3026Y-290190D01*
X-4985D01*
G01X-3026D02*
X-1851Y-293235D01*
G01X1159D02*
Y-286935D01*
X2725D01*
X3352Y-287250D01*
X3822Y-287670D01*
X4214Y-288300D01*
X4527Y-289035D01*
X4605Y-290085D01*
X4527Y-291135D01*
X4214Y-291870D01*
X3822Y-292500D01*
X3352Y-292920D01*
X2725Y-293235D01*
X1159D01*
G01X9182Y-293445D02*
X9025Y-293340D01*
Y-293130D01*
X9182Y-293025D01*
X9339Y-293130D01*
Y-293340D01*
X9182Y-293445D01*
G01X-116348Y-300085D02*
X-114781D01*
Y-301975D01*
X-115251Y-302605D01*
X-115800Y-303025D01*
X-116583Y-303235D01*
X-117366Y-303025D01*
X-117915Y-302605D01*
X-118385Y-301975D01*
X-118698Y-301240D01*
X-118855Y-300400D01*
Y-299665D01*
X-118698Y-299035D01*
X-118385Y-298300D01*
X-117915Y-297670D01*
X-117445Y-297250D01*
X-116818Y-296935D01*
X-116270D01*
X-115643Y-297145D01*
X-115173Y-297565D01*
G01X-112241Y-296935D02*
Y-301450D01*
X-111928Y-302395D01*
X-111301Y-303025D01*
X-110518Y-303235D01*
X-109735Y-303025D01*
X-109108Y-302395D01*
X-108795Y-301450D01*
Y-296935D01*
G01X-105158D02*
X-103278D01*
G01X-104218D02*
Y-303235D01*
G01X-105158D02*
X-103278D01*
G01X-99563Y-302395D02*
X-98936Y-302920D01*
X-98231Y-303235D01*
X-97605D01*
X-96978Y-302920D01*
X-96508Y-302395D01*
X-96273Y-301660D01*
X-96430Y-300925D01*
X-96821Y-300295D01*
X-97526Y-299875D01*
X-98466Y-299665D01*
X-99015Y-299245D01*
X-99250Y-298510D01*
X-99093Y-297775D01*
X-98701Y-297250D01*
X-98153Y-296935D01*
X-97605D01*
X-97056Y-297145D01*
X-96586Y-297670D01*
G01X-93263Y-303235D02*
Y-296935D01*
G01X-89973D02*
Y-303235D01*
G01Y-300085D02*
X-93263D01*
G01X-87276Y-303235D02*
X-85318Y-296935D01*
X-83360Y-303235D01*
G01X-84065Y-301030D02*
X-86571D01*
G01X-80820Y-303235D02*
Y-296935D01*
X-77216Y-303235D01*
Y-296935D01*
G01X-68141Y-303235D02*
Y-296935D01*
X-66575D01*
X-65948Y-297250D01*
X-65478Y-297670D01*
X-65086Y-298300D01*
X-64773Y-299035D01*
X-64695Y-300085D01*
X-64773Y-301135D01*
X-65086Y-301870D01*
X-65478Y-302500D01*
X-65948Y-302920D01*
X-66575Y-303235D01*
X-68141D01*
G01X-61058Y-296935D02*
X-59178D01*
G01X-60118D02*
Y-303235D01*
G01X-61058D02*
X-59178D01*
G01X-55463Y-302395D02*
X-54836Y-302920D01*
X-54131Y-303235D01*
X-53505D01*
X-52878Y-302920D01*
X-52408Y-302395D01*
X-52173Y-301660D01*
X-52330Y-300925D01*
X-52721Y-300295D01*
X-53426Y-299875D01*
X-54366Y-299665D01*
X-54915Y-299245D01*
X-55150Y-298510D01*
X-54993Y-297775D01*
X-54601Y-297250D01*
X-54053Y-296935D01*
X-53505D01*
X-52956Y-297145D01*
X-52486Y-297670D01*
G01X-47518Y-296935D02*
Y-303235D01*
G01X-49320Y-296935D02*
X-45716D01*
G01X-41218Y-303445D02*
X-41375Y-303340D01*
Y-303130D01*
X-41218Y-303025D01*
X-41061Y-303130D01*
Y-303340D01*
X-41218Y-303445D01*
G01X-35075Y-304390D02*
X-34761Y-303025D01*
G01X-28618Y-296935D02*
Y-303235D01*
G01X-30420Y-296935D02*
X-26816D01*
G01X-24276Y-303235D02*
X-22318Y-296935D01*
X-20360Y-303235D01*
G01X-21065Y-301030D02*
X-23571D01*
G01X-16018Y-303235D02*
X-16645Y-303130D01*
X-17193Y-302710D01*
X-17663Y-302080D01*
X-17976Y-301345D01*
X-18133Y-300505D01*
Y-299665D01*
X-17976Y-298825D01*
X-17663Y-298090D01*
X-17193Y-297460D01*
X-16645Y-297040D01*
X-16018Y-296935D01*
X-15391Y-297040D01*
X-14843Y-297460D01*
X-14373Y-298090D01*
X-14060Y-298825D01*
X-13903Y-299665D01*
Y-300505D01*
X-14060Y-301345D01*
X-14373Y-302080D01*
X-14843Y-302710D01*
X-15391Y-303130D01*
X-16018Y-303235D01*
G01X-9718D02*
Y-300400D01*
X-11285Y-296935D01*
G01X-8151D02*
X-9718Y-300400D01*
G01X-5141Y-296935D02*
Y-301450D01*
X-4828Y-302395D01*
X-4201Y-303025D01*
X-3418Y-303235D01*
X-2635Y-303025D01*
X-2008Y-302395D01*
X-1695Y-301450D01*
Y-296935D01*
G01X924Y-303235D02*
X2882Y-296935D01*
X4840Y-303235D01*
G01X4135Y-301030D02*
X1629D01*
G01X7380Y-303235D02*
Y-296935D01*
X10984Y-303235D01*
Y-296935D01*
G01X-94518Y-282535D02*
X-97038Y-282118D01*
X-99243Y-280452D01*
X-101133Y-277952D01*
X-102393Y-275035D01*
X-103023Y-271702D01*
Y-268368D01*
X-102393Y-265035D01*
X-101133Y-262118D01*
X-99243Y-259619D01*
X-97038Y-257952D01*
X-94518Y-257535D01*
X-91998Y-257952D01*
X-89793Y-259619D01*
X-87903Y-262118D01*
X-86643Y-265035D01*
X-86013Y-268368D01*
Y-271702D01*
X-86643Y-275035D01*
X-87903Y-277952D01*
X-89793Y-280452D01*
X-91998Y-282118D01*
X-94518Y-282535D01*
G01X-91998Y-275868D02*
X-88218Y-282535D01*
G01X-74673Y-265869D02*
Y-277535D01*
X-73413Y-280452D01*
X-71523Y-282118D01*
X-69318Y-282535D01*
X-67113Y-282118D01*
X-65223Y-280452D01*
X-63963Y-277535D01*
G01Y-282535D02*
Y-265869D01*
G01X-38448Y-282535D02*
Y-265869D01*
G01Y-268785D02*
X-39708Y-267119D01*
X-41598Y-266285D01*
X-43803Y-265869D01*
X-46008Y-266702D01*
X-47898Y-268368D01*
X-49158Y-270869D01*
X-49788Y-274202D01*
X-49158Y-277535D01*
X-47898Y-280036D01*
X-46008Y-281702D01*
X-43803Y-282535D01*
X-41598Y-282118D01*
X-39708Y-280869D01*
X-38448Y-279202D01*
G01X-24273Y-282535D02*
Y-265869D01*
G01Y-270035D02*
X-23013Y-267952D01*
X-21123Y-266285D01*
X-18603Y-265869D01*
X-16398Y-266285D01*
X-14508Y-267952D01*
X-13563Y-270869D01*
Y-282535D01*
G01X6282Y-257535D02*
Y-282535D01*
G01X1872Y-265869D02*
X10692D01*
G01X37152Y-282535D02*
Y-265869D01*
G01Y-268785D02*
X35892Y-267119D01*
X34002Y-266285D01*
X31797Y-265869D01*
X29592Y-266702D01*
X27702Y-268368D01*
X26442Y-270869D01*
X25812Y-274202D01*
X26442Y-277535D01*
X27702Y-280036D01*
X29592Y-281702D01*
X31797Y-282535D01*
X34002Y-282118D01*
X35892Y-280869D01*
X37152Y-279202D01*
G01X76832Y-262235D02*
Y-270235D01*
X80832D01*
G01X88632D02*
Y-264902D01*
G01Y-265835D02*
X88232Y-265302D01*
X87632Y-265035D01*
X86932Y-264902D01*
X86232Y-265168D01*
X85632Y-265702D01*
X85232Y-266502D01*
X85032Y-267568D01*
X85232Y-268635D01*
X85632Y-269435D01*
X86232Y-269968D01*
X86932Y-270235D01*
X87632Y-270102D01*
X88232Y-269702D01*
X88632Y-269169D01*
G01X92732Y-272635D02*
X93332Y-272902D01*
X94132Y-272635D01*
X94632Y-272102D01*
X95032Y-271435D01*
X95632Y-269302D01*
X96932Y-264902D01*
G01X93732D02*
X95632Y-269302D01*
G01X101332Y-266635D02*
X104532D01*
X104232Y-265702D01*
X103732Y-265168D01*
X103032Y-264902D01*
X102332Y-265035D01*
X101732Y-265435D01*
X101332Y-266368D01*
X101132Y-267169D01*
Y-267968D01*
X101332Y-268768D01*
X101832Y-269568D01*
X102432Y-270102D01*
X103132Y-270235D01*
X103832Y-269968D01*
X104532Y-269169D01*
G01X109432Y-270235D02*
Y-264902D01*
G01Y-265968D02*
X109932Y-265435D01*
X110432Y-265035D01*
X111132Y-264902D01*
X111632Y-265035D01*
X112232Y-265435D01*
G01X95532Y-320235D02*
Y-312235D01*
X100132Y-320235D01*
Y-312235D01*
G01X105832Y-314902D02*
Y-320235D01*
G01Y-312768D02*
X105632Y-312635D01*
Y-312368D01*
X105832Y-312235D01*
X106032Y-312368D01*
Y-312635D01*
X105832Y-312768D01*
G01X112132Y-320235D02*
Y-314902D01*
G01Y-316235D02*
X112532Y-315568D01*
X113132Y-315035D01*
X113932Y-314902D01*
X114632Y-315035D01*
X115232Y-315568D01*
X115532Y-316502D01*
Y-320235D01*
G01X123632D02*
Y-314902D01*
G01Y-315835D02*
X123232Y-315302D01*
X122632Y-315035D01*
X121932Y-314902D01*
X121232Y-315168D01*
X120632Y-315702D01*
X120232Y-316502D01*
X120032Y-317568D01*
X120232Y-318635D01*
X120632Y-319435D01*
X121232Y-319968D01*
X121932Y-320235D01*
X122632Y-320102D01*
X123232Y-319702D01*
X123632Y-319169D01*
G01X88332Y-295235D02*
Y-287235D01*
X90732D01*
X91532Y-287635D01*
X92132Y-288568D01*
X92332Y-289635D01*
X92132Y-290702D01*
X91632Y-291502D01*
X90732Y-291902D01*
X88332D01*
G01X95832Y-295235D02*
X98332Y-287235D01*
X100832Y-295235D01*
G01X99932Y-292435D02*
X96732D01*
G01X104232Y-294169D02*
X105032Y-294835D01*
X105932Y-295235D01*
X106732D01*
X107532Y-294835D01*
X108132Y-294169D01*
X108432Y-293235D01*
X108232Y-292302D01*
X107732Y-291502D01*
X106832Y-290968D01*
X105632Y-290702D01*
X104932Y-290168D01*
X104632Y-289235D01*
X104832Y-288302D01*
X105332Y-287635D01*
X106032Y-287235D01*
X106732D01*
X107432Y-287502D01*
X108032Y-288168D01*
G01X114332Y-287235D02*
Y-295235D01*
G01X112032Y-287235D02*
X116632D01*
G01X121032Y-292568D02*
X123632D01*
G01X131132Y-290968D02*
X131532Y-290568D01*
X131832Y-289902D01*
X132032Y-288968D01*
X131832Y-288168D01*
X131432Y-287635D01*
X130732Y-287235D01*
X128032D01*
Y-295235D01*
X131332D01*
X132032Y-294702D01*
X132432Y-293902D01*
X132632Y-292968D01*
X132432Y-292035D01*
X131832Y-291235D01*
X131132Y-290968D01*
X128032D01*
G01X138332Y-295235D02*
X137532Y-295102D01*
X136832Y-294568D01*
X136232Y-293768D01*
X135832Y-292835D01*
X135632Y-291768D01*
Y-290702D01*
X135832Y-289635D01*
X136232Y-288702D01*
X136832Y-287902D01*
X137532Y-287368D01*
X138332Y-287235D01*
X139132Y-287368D01*
X139832Y-287902D01*
X140432Y-288702D01*
X140832Y-289635D01*
X141032Y-290702D01*
Y-291768D01*
X140832Y-292835D01*
X140432Y-293768D01*
X139832Y-294568D01*
X139132Y-295102D01*
X138332Y-295235D01*
G01X146332Y-287235D02*
Y-295235D01*
G01X144032Y-287235D02*
X148632D01*
G01X203432Y-313568D02*
X204032Y-312768D01*
X204732Y-312368D01*
X205532Y-312235D01*
X206532Y-312502D01*
X207232Y-313168D01*
X207432Y-313968D01*
X207332Y-314769D01*
X206932Y-315435D01*
X204932Y-316768D01*
X204032Y-317702D01*
X203432Y-319035D01*
X203232Y-320235D01*
X207432D01*
G01X213332Y-312235D02*
X212532Y-312502D01*
X211932Y-313168D01*
X211532Y-313968D01*
X211232Y-315035D01*
X211132Y-316235D01*
X211232Y-317435D01*
X211532Y-318502D01*
X211932Y-319302D01*
X212532Y-319968D01*
X213332Y-320235D01*
X214132Y-319968D01*
X214732Y-319302D01*
X215132Y-318502D01*
X215432Y-317435D01*
X215532Y-316235D01*
X215432Y-315035D01*
X215132Y-313968D01*
X214732Y-313168D01*
X214132Y-312502D01*
X213332Y-312235D01*
G01X219432Y-313568D02*
X220032Y-312768D01*
X220732Y-312368D01*
X221532Y-312235D01*
X222532Y-312502D01*
X223232Y-313168D01*
X223432Y-313968D01*
X223332Y-314769D01*
X222932Y-315435D01*
X220932Y-316768D01*
X220032Y-317702D01*
X219432Y-319035D01*
X219232Y-320235D01*
X223432D01*
G01X227432Y-313568D02*
X228032Y-312768D01*
X228732Y-312368D01*
X229532Y-312235D01*
X230532Y-312502D01*
X231232Y-313168D01*
X231432Y-313968D01*
X231332Y-314769D01*
X230932Y-315435D01*
X228932Y-316768D01*
X228032Y-317702D01*
X227432Y-319035D01*
X227232Y-320235D01*
X231432D01*
G01X235532Y-320502D02*
X239132Y-312235D01*
G01X245332Y-320235D02*
Y-312235D01*
X244132Y-313835D01*
G01Y-320235D02*
X246532D01*
G01X251432Y-313568D02*
X252032Y-312768D01*
X252732Y-312368D01*
X253532Y-312235D01*
X254532Y-312502D01*
X255232Y-313168D01*
X255432Y-313968D01*
X255332Y-314769D01*
X254932Y-315435D01*
X252932Y-316768D01*
X252032Y-317702D01*
X251432Y-319035D01*
X251232Y-320235D01*
X255432D01*
G01X259532Y-320502D02*
X263132Y-312235D01*
G01X269332D02*
X268532Y-312502D01*
X267932Y-313168D01*
X267532Y-313968D01*
X267232Y-315035D01*
X267132Y-316235D01*
X267232Y-317435D01*
X267532Y-318502D01*
X267932Y-319302D01*
X268532Y-319968D01*
X269332Y-320235D01*
X270132Y-319968D01*
X270732Y-319302D01*
X271132Y-318502D01*
X271432Y-317435D01*
X271532Y-316235D01*
X271432Y-315035D01*
X271132Y-313968D01*
X270732Y-313168D01*
X270132Y-312502D01*
X269332Y-312235D01*
G01X275632Y-319302D02*
X276332Y-319968D01*
X277132Y-320235D01*
X277932Y-319968D01*
X278632Y-319169D01*
X279132Y-317968D01*
X279332Y-316768D01*
Y-315302D01*
X279132Y-314102D01*
X278632Y-313035D01*
X278032Y-312502D01*
X277332Y-312235D01*
X276532Y-312502D01*
X275932Y-313035D01*
X275532Y-313835D01*
X275332Y-314902D01*
X275532Y-315835D01*
X276032Y-316768D01*
X276632Y-317302D01*
X277332Y-317435D01*
X278132Y-317169D01*
X278732Y-316502D01*
X279332Y-315302D01*
G01X205632Y-295235D02*
Y-287235D01*
X207632D01*
X208432Y-287635D01*
X209032Y-288168D01*
X209532Y-288968D01*
X209932Y-289902D01*
X210032Y-291235D01*
X209932Y-292568D01*
X209532Y-293502D01*
X209032Y-294302D01*
X208432Y-294835D01*
X207632Y-295235D01*
X205632D01*
G01X213332D02*
X215832Y-287235D01*
X218332Y-295235D01*
G01X217432Y-292435D02*
X214232D01*
G01X223832Y-287235D02*
X223032Y-287502D01*
X222432Y-288168D01*
X222032Y-288968D01*
X221732Y-290035D01*
X221632Y-291235D01*
X221732Y-292435D01*
X222032Y-293502D01*
X222432Y-294302D01*
X223032Y-294968D01*
X223832Y-295235D01*
X224632Y-294968D01*
X225232Y-294302D01*
X225632Y-293502D01*
X225932Y-292435D01*
X226032Y-291235D01*
X225932Y-290035D01*
X225632Y-288968D01*
X225232Y-288168D01*
X224632Y-287502D01*
X223832Y-287235D01*
G01X229932Y-295235D02*
Y-287235D01*
X233732D01*
G01X232332Y-291102D02*
X229932D01*
G01X239832Y-287235D02*
X239032Y-287502D01*
X238432Y-288168D01*
X238032Y-288968D01*
X237732Y-290035D01*
X237632Y-291235D01*
X237732Y-292435D01*
X238032Y-293502D01*
X238432Y-294302D01*
X239032Y-294968D01*
X239832Y-295235D01*
X240632Y-294968D01*
X241232Y-294302D01*
X241632Y-293502D01*
X241932Y-292435D01*
X242032Y-291235D01*
X241932Y-290035D01*
X241632Y-288968D01*
X241232Y-288168D01*
X240632Y-287502D01*
X239832Y-287235D01*
G01X247832D02*
Y-295235D01*
G01X245532Y-287235D02*
X250132D01*
G01X255832Y-295235D02*
Y-291635D01*
X253832Y-287235D01*
G01X257832D02*
X255832Y-291635D01*
G01X264632Y-290968D02*
X265032Y-290568D01*
X265332Y-289902D01*
X265532Y-288968D01*
X265332Y-288168D01*
X264932Y-287635D01*
X264232Y-287235D01*
X261532D01*
Y-295235D01*
X264832D01*
X265532Y-294702D01*
X265932Y-293902D01*
X266132Y-292968D01*
X265932Y-292035D01*
X265332Y-291235D01*
X264632Y-290968D01*
X261532D01*
G01X273032Y-295235D02*
Y-287235D01*
X269332Y-292968D01*
X274332D01*
G01X277632Y-295235D02*
Y-287235D01*
X279632D01*
X280432Y-287635D01*
X281032Y-288168D01*
X281532Y-288968D01*
X281932Y-289902D01*
X282032Y-291235D01*
X281932Y-292568D01*
X281532Y-293502D01*
X281032Y-294302D01*
X280432Y-294835D01*
X279632Y-295235D01*
X277632D01*
G01X287832Y-287235D02*
X287032Y-287502D01*
X286432Y-288168D01*
X286032Y-288968D01*
X285732Y-290035D01*
X285632Y-291235D01*
X285732Y-292435D01*
X286032Y-293502D01*
X286432Y-294302D01*
X287032Y-294968D01*
X287832Y-295235D01*
X288632Y-294968D01*
X289232Y-294302D01*
X289632Y-293502D01*
X289932Y-292435D01*
X290032Y-291235D01*
X289932Y-290035D01*
X289632Y-288968D01*
X289232Y-288168D01*
X288632Y-287502D01*
X287832Y-287235D01*
G01X233432Y-270235D02*
Y-262235D01*
X237232D01*
G01X235832Y-266102D02*
X233432D01*
G01X243332Y-262235D02*
X242532Y-262502D01*
X241932Y-263168D01*
X241532Y-263968D01*
X241232Y-265035D01*
X241132Y-266235D01*
X241232Y-267435D01*
X241532Y-268502D01*
X241932Y-269302D01*
X242532Y-269968D01*
X243332Y-270235D01*
X244132Y-269968D01*
X244732Y-269302D01*
X245132Y-268502D01*
X245432Y-267435D01*
X245532Y-266235D01*
X245432Y-265035D01*
X245132Y-263968D01*
X244732Y-263168D01*
X244132Y-262502D01*
X243332Y-262235D01*
G01X251332D02*
Y-270235D01*
G01X249032Y-262235D02*
X253632D01*
G01X256332Y-272902D02*
X262332D01*
G01X265332Y-270235D02*
Y-262235D01*
X267732D01*
X268532Y-262635D01*
X269132Y-263568D01*
X269332Y-264635D01*
X269132Y-265702D01*
X268632Y-266502D01*
X267732Y-266902D01*
X265332D01*
G01X272832Y-270235D02*
X275332Y-262235D01*
X277832Y-270235D01*
G01X276932Y-267435D02*
X273732D01*
G01X281032Y-270235D02*
Y-262235D01*
X285632Y-270235D01*
Y-262235D01*
G01X293332Y-270235D02*
X289332D01*
Y-262235D01*
X293332D01*
G01X291732Y-266102D02*
X289332D01*
G01X297332Y-262235D02*
Y-270235D01*
X301332D01*
G01X304332Y-272902D02*
X310332D01*
G01X316132Y-265968D02*
X316532Y-265568D01*
X316832Y-264902D01*
X317032Y-263968D01*
X316832Y-263168D01*
X316432Y-262635D01*
X315732Y-262235D01*
X313032D01*
Y-270235D01*
X316332D01*
X317032Y-269702D01*
X317432Y-268902D01*
X317632Y-267968D01*
X317432Y-267035D01*
X316832Y-266235D01*
X316132Y-265968D01*
X313032D01*
G01X321132Y-270235D02*
Y-262235D01*
X323132D01*
X323932Y-262635D01*
X324532Y-263168D01*
X325032Y-263968D01*
X325432Y-264902D01*
X325532Y-266235D01*
X325432Y-267568D01*
X325032Y-268502D01*
X324532Y-269302D01*
X323932Y-269835D01*
X323132Y-270235D01*
X321132D01*
G01X291832Y-323235D02*
Y-315235D01*
X290632Y-316835D01*
G01Y-323235D02*
X293032D01*
G01X297932Y-319902D02*
X298632Y-318968D01*
X299232Y-318435D01*
X300032Y-318168D01*
X300732Y-318435D01*
X301232Y-318968D01*
X301632Y-319768D01*
X301732Y-320702D01*
X301632Y-321502D01*
X301232Y-322302D01*
X300632Y-322968D01*
X299932Y-323235D01*
X299132Y-322968D01*
X298432Y-322169D01*
X298032Y-320968D01*
X297932Y-319635D01*
X298132Y-317902D01*
X298432Y-316968D01*
X298932Y-316035D01*
X299632Y-315368D01*
X300332Y-315235D01*
X301032Y-315502D01*
X301532Y-316168D01*
G01X307832Y-323502D02*
X307632Y-323368D01*
Y-323102D01*
X307832Y-322968D01*
X308032Y-323102D01*
Y-323368D01*
X307832Y-323502D01*
G01X313932Y-319902D02*
X314632Y-318968D01*
X315232Y-318435D01*
X316032Y-318168D01*
X316732Y-318435D01*
X317232Y-318968D01*
X317632Y-319768D01*
X317732Y-320702D01*
X317632Y-321502D01*
X317232Y-322302D01*
X316632Y-322968D01*
X315932Y-323235D01*
X315132Y-322968D01*
X314432Y-322169D01*
X314032Y-320968D01*
X313932Y-319635D01*
X314132Y-317902D01*
X314432Y-316968D01*
X314932Y-316035D01*
X315632Y-315368D01*
X316332Y-315235D01*
X317032Y-315502D01*
X317532Y-316168D01*
G01X336832Y-323235D02*
Y-315235D01*
X335632Y-316835D01*
G01Y-323235D02*
X338032D01*
G01X344632D02*
X344832Y-321502D01*
X345132Y-320035D01*
X345532Y-318702D01*
X346032Y-317235D01*
X346832Y-315235D01*
X342832D01*
G01X352832Y-323502D02*
X352632Y-323368D01*
Y-323102D01*
X352832Y-322968D01*
X353032Y-323102D01*
Y-323368D01*
X352832Y-323502D01*
G01X358932Y-316568D02*
X359532Y-315768D01*
X360232Y-315368D01*
X361032Y-315235D01*
X362032Y-315502D01*
X362732Y-316168D01*
X362932Y-316968D01*
X362832Y-317769D01*
X362432Y-318435D01*
X360432Y-319768D01*
X359532Y-320702D01*
X358932Y-322035D01*
X358732Y-323235D01*
X362932D01*
G01X356632Y-298235D02*
Y-290235D01*
X358632D01*
X359432Y-290635D01*
X360032Y-291168D01*
X360532Y-291968D01*
X360932Y-292902D01*
X361032Y-294235D01*
X360932Y-295568D01*
X360532Y-296502D01*
X360032Y-297302D01*
X359432Y-297835D01*
X358632Y-298235D01*
X356632D01*
G54D11*
X8000Y99500D03*
Y110500D03*
X16000Y109441D03*
X12500Y117000D03*
X11500Y200000D03*
Y192000D03*
Y184000D03*
X33000Y186000D03*
X19500Y221500D03*
Y213500D03*
X59586Y40000D03*
X59500Y55000D03*
X48941Y89500D03*
X52000Y81000D03*
X59500Y95000D03*
X54059Y102500D03*
X41500Y103500D03*
X41038Y112537D03*
X41000Y213532D03*
X59075Y204000D03*
X56500Y261000D03*
X55000Y276000D03*
X81000Y8000D03*
X72555Y46921D03*
X70075Y64500D03*
X68720Y54000D03*
X81729Y77772D03*
X64075Y200000D03*
X66500Y189500D03*
X68500Y231500D03*
X69075Y247000D03*
X78937Y270653D03*
X75394Y288205D03*
X99500Y9000D03*
X91000Y18500D03*
X98000Y99000D03*
X93111Y288205D03*
X86024Y270653D03*
X93111D03*
X84843Y288205D03*
X101500Y277500D03*
X118500Y6716D03*
X113181Y31701D03*
X106954Y21716D03*
X111965Y11716D03*
X109812Y16716D03*
X117000Y122500D03*
X132000Y10500D03*
X139500D03*
X127500Y6716D03*
X134500Y105000D03*
Y119000D03*
X140000Y177500D03*
X132500Y185000D03*
X140000D03*
X132500Y192500D03*
X140000D03*
X132500Y200000D03*
X140000D03*
Y215000D03*
X132500Y207500D03*
X140000D03*
X132500Y215000D03*
X148500Y84000D03*
X147500Y177500D03*
Y200000D03*
Y185000D03*
Y192500D03*
Y222500D03*
Y215000D03*
Y207500D03*
G54D12*
X20315Y20079D03*
X43937D03*
G54D13*
X57480Y26299D03*
X67480D03*
G54D14*
X77480D03*
G54D15*
X61516Y326772D03*
Y314961D03*
X110532Y326772D03*
Y314961D03*
G54D16*
X87756Y47244D03*
X109095Y89370D03*
G54D17*
X101969Y52480D03*
Y68228D03*
Y60354D03*
X94882Y54449D03*
Y64291D03*
Y72165D03*
X101969Y83976D03*
Y76102D03*
G54D18*
X87756Y89370D03*
X109095Y47244D03*
G54D19*
X94882Y82008D03*
M02*
